# BASEBOARD_FAB2 (Tioga Pass) — schematic netlist excerpt (pin names and nets, part order shuffled) for the footprints in the layout excerpt that follows; sources: Cadence DE-HDL packaged netlist, KiCad conversion of Wiwynn_Tioga_Pass_MB.brd

C5G66  CAP_A  22.0UF 4V 20% X6S  pkg 0603V  page 242 : A = PVDDQ_DEF ; B = GND
C2P12  CAP_A  0.1UF 16V 10% X7R  pkg 0402V  page 188 : A = P12V_STBY ; B = GND
C5P43  CAP  100UF 4V 20% X5R  pkg 0805  page 217 : A = PVDDQ_ABC ; B = GND

(kicad_pcb
	(version 20260206)
	(generator "pcbnew")
	(generator_version "10.0")
	(general
		(thickness 1.6)
		(legacy_teardrops no)
	)
	(paper "A4")
	(title_block
		(title "Wiwynn_Tioga_Pass_MB.brd")
		(comment 1 "Tioga Pass / footprints 4754-4756 of 4770")
	)
	(layers
		(0 "F.Cu" signal "TOP")
		(4 "In1.Cu" signal "L2GND")
		(6 "In2.Cu" signal "L3")
		(8 "In3.Cu" signal "L4GND")
		(10 "In4.Cu" signal "L5")
		(12 "In5.Cu" signal "L6GND")
		(14 "In6.Cu" signal "L7VCC")
		(16 "In7.Cu" signal "L8VCC")
		(18 "In8.Cu" signal "L9GND")
		(20 "In9.Cu" signal "L10")
		(22 "In10.Cu" signal "L11GND")
		(24 "In11.Cu" signal "L12")
		(26 "In12.Cu" signal "L13GND")
		(2 "B.Cu" signal "BOTTOM")
		(9 "F.Adhes" user "F.Adhesive")
		(11 "B.Adhes" user "B.Adhesive")
		(13 "F.Paste" user "Package Geometry/Pastemask Top")
		(15 "B.Paste" user "Package Geometry/Pastemask Bottom")
		(5 "F.SilkS" user "Ref Des/Silkscreen Top")
		(7 "B.SilkS" user "Ref Des/Silkscreen Bottom")
		(1 "F.Mask" user "Board Geometry/Soldermask Top")
		(3 "B.Mask" user "Board Geometry/Soldermask Bottom")
		(17 "Dwgs.User" user "User.Drawings")
		(19 "Cmts.User" user "User.Comments")
		(21 "Eco1.User" user "User.Eco1")
		(23 "Eco2.User" user "User.Eco2")
		(25 "Edge.Cuts" user "Board Geometry/Outline")
		(27 "Margin" user)
		(31 "F.CrtYd" user "Package Geometry/Place Bound Top")
		(29 "B.CrtYd" user "Package Geometry/Place Bound Bottom")
		(35 "F.Fab" user "Ref Des/Assembly Top")
		(33 "B.Fab" user "Ref Des/Assembly Bottom")
	)
	(footprint ""
		(layer "B.Cu")
		(at 446.33388 -64.752982 180)
		(property "Reference" "C2P12"
			(at 0 0 0)
			(layer "B.SilkS")
			(hide yes)
			(effects
				(font
					(size 1.27 1.27)
				)
				(justify mirror)
			)
		)
		(property "Value" ""
			(at 0 0 0)
			(layer "B.Fab")
			(effects
				(font
					(size 1.27 1.27)
				)
				(justify mirror)
			)
		)
		(duplicate_pad_numbers_are_jumpers no)
		(fp_poly
			(pts
				(xy -0.3048 -0.1016) (xy -0.3048 0.9906) (xy 0.3048 0.9906) (xy 0.3048 -0.1016)
			)
			(stroke
				(width 0)
				(type default)
			)
			(fill no)
			(layer "B.CrtYd")
		)
		(fp_line
			(start 0.3048 0.9906)
			(end -0.3048 0.9906)
			(stroke
				(width 0.1)
				(type default)
			)
			(layer "B.Fab")
		)
		(fp_line
			(start 0.3048 -0.1016)
			(end 0.3048 0.9906)
			(stroke
				(width 0.1)
				(type default)
			)
			(layer "B.Fab")
		)
		(fp_line
			(start -0.3048 0.9906)
			(end -0.3048 -0.1016)
			(stroke
				(width 0.1)
				(type default)
			)
			(layer "B.Fab")
		)
		(fp_line
			(start -0.3048 -0.1016)
			(end 0.3048 -0.1016)
			(stroke
				(width 0.1)
				(type default)
			)
			(layer "B.Fab")
		)
		(pad "1" smd rect
			(at 0 0)
			(size 0.508 0.508)
			(layers "B.Cu" "B.Mask" "B.Paste")
			(net "P12V_STBY")
		)
		(pad "2" smd rect
			(at 0 0.889)
			(size 0.508 0.508)
			(layers "B.Cu" "B.Mask" "B.Paste")
			(net "GND")
		)
		(zone
			(layer "B.Cu")
			(hatch none 0.5)
			(connect_pads
				(clearance 0)
			)
			(min_thickness 0.25)
			(keepout
				(tracks not_allowed)
				(vias allowed)
				(pads allowed)
				(copperpour not_allowed)
				(footprints allowed)
			)
			(placement
				(enabled no)
				(sheetname "")
			)
			(fill
				(thermal_gap 0.5)
				(thermal_bridge_width 0.5)
				(island_removal_mode 0)
			)
			(polygon
				(pts
					(xy 446.07988 -65.387982) (xy 446.58788 -65.387982) (xy 446.58788 -65.006982) (xy 446.07988 -65.006982)
				)
			)
		)
		(zone
			(layer "B.Cu")
			(hatch none 0.5)
			(connect_pads
				(clearance 0)
			)
			(min_thickness 0.25)
			(keepout
				(tracks allowed)
				(vias not_allowed)
				(pads allowed)
				(copperpour not_allowed)
				(footprints allowed)
			)
			(placement
				(enabled no)
				(sheetname "")
			)
			(fill
				(thermal_gap 0.5)
				(thermal_bridge_width 0.5)
				(island_removal_mode 0)
			)
			(polygon
				(pts
					(xy 446.07988 -65.006982) (xy 446.58788 -65.006982) (xy 446.58788 -65.387982) (xy 446.07988 -65.387982)
				)
			)
		)
	)
	(footprint ""
		(layer "B.Cu")
		(at 269.775686 -68.17614 180)
		(property "Reference" "C5P43"
			(at 0 0 0)
			(layer "B.SilkS")
			(hide yes)
			(effects
				(font
					(size 1.27 1.27)
				)
				(justify mirror)
			)
		)
		(property "Value" ""
			(at 0 0 0)
			(layer "B.Fab")
			(effects
				(font
					(size 1.27 1.27)
				)
				(justify mirror)
			)
		)
		(duplicate_pad_numbers_are_jumpers no)
		(fp_poly
			(pts
				(xy 0.7239 -0.2159) (xy -0.7239 -0.2159) (xy -0.7239 1.9939) (xy 0.7239 1.9939)
			)
			(stroke
				(width 0)
				(type default)
			)
			(fill no)
			(layer "B.CrtYd")
		)
		(fp_line
			(start 0.7239 1.9939)
			(end -0.7239 1.9939)
			(stroke
				(width 0.1)
				(type default)
			)
			(layer "B.Fab")
		)
		(fp_line
			(start 0.7239 -0.2159)
			(end 0.7239 1.9939)
			(stroke
				(width 0.1)
				(type default)
			)
			(layer "B.Fab")
		)
		(fp_line
			(start -0.7239 1.9939)
			(end -0.7239 -0.2159)
			(stroke
				(width 0.1)
				(type default)
			)
			(layer "B.Fab")
		)
		(fp_line
			(start -0.7239 -0.2159)
			(end 0.7239 -0.2159)
			(stroke
				(width 0.1)
				(type default)
			)
			(layer "B.Fab")
		)
		(pad "1" smd rect
			(at 0 0)
			(size 1.27 1.016)
			(layers "B.Cu" "B.Mask" "B.Paste")
			(net "PVDDQ_ABC")
		)
		(pad "2" smd rect
			(at 0 1.778)
			(size 1.27 1.016)
			(layers "B.Cu" "B.Mask" "B.Paste")
			(net "GND")
		)
		(zone
			(layer "B.Cu")
			(hatch none 0.5)
			(connect_pads
				(clearance 0)
			)
			(min_thickness 0.25)
			(keepout
				(tracks not_allowed)
				(vias allowed)
				(pads allowed)
				(copperpour not_allowed)
				(footprints allowed)
			)
			(placement
				(enabled no)
				(sheetname "")
			)
			(fill
				(thermal_gap 0.5)
				(thermal_bridge_width 0.5)
				(island_removal_mode 0)
			)
			(polygon
				(pts
					(xy 269.140686 -68.68414) (xy 270.410686 -68.68414) (xy 270.410686 -69.44614) (xy 269.140686 -69.44614)
				)
			)
		)
	)
	(footprint ""
		(layer "B.Cu")
		(at 252.1585 -140.208 -90)
		(property "Reference" "C5G66"
			(at -1.14681 0.76708 0)
			(unlocked yes)
			(layer "B.SilkS")
			(effects
				(font
					(size 0.7874 0.5842)
					(thickness 0.1524)
				)
				(justify mirror)
			)
		)
		(property "Value" ""
			(at 0 0 90)
			(layer "B.Fab")
			(effects
				(font
					(size 1.27 1.27)
				)
				(justify mirror)
			)
		)
		(duplicate_pad_numbers_are_jumpers no)
		(fp_rect
			(start 0.4953 1.6002)
			(end -0.4953 -0.2032)
			(stroke
				(width 0)
				(type default)
			)
			(fill no)
			(layer "B.CrtYd")
		)
		(fp_line
			(start -0.4953 1.6002)
			(end 0.4953 1.6002)
			(stroke
				(width 0.1)
				(type default)
			)
			(layer "B.Fab")
		)
		(fp_line
			(start 0.4953 1.6002)
			(end 0.4953 -0.2032)
			(stroke
				(width 0.1)
				(type default)
			)
			(layer "B.Fab")
		)
		(fp_line
			(start -0.4953 -0.2032)
			(end -0.4953 1.6002)
			(stroke
				(width 0.1)
				(type default)
			)
			(layer "B.Fab")
		)
		(fp_line
			(start 0.4953 -0.2032)
			(end -0.4953 -0.2032)
			(stroke
				(width 0.1)
				(type default)
			)
			(layer "B.Fab")
		)
		(pad "1" smd rect
			(at 0 0 90)
			(size 0.762 0.889)
			(layers "B.Cu" "B.Mask" "B.Paste")
			(net "PVDDQ_DEF")
		)
		(pad "2" smd rect
			(at 0 1.397 90)
			(size 0.762 0.889)
			(layers "B.Cu" "B.Mask" "B.Paste")
			(net "GND")
		)
		(zone
			(layer "B.Cu")
			(hatch none 0.5)
			(connect_pads
				(clearance 0)
			)
			(min_thickness 0.25)
			(keepout
				(tracks not_allowed)
				(vias allowed)
				(pads allowed)
				(copperpour not_allowed)
				(footprints allowed)
			)
			(placement
				(enabled no)
				(sheetname "")
			)
			(fill
				(thermal_gap 0.5)
				(thermal_bridge_width 0.5)
				(island_removal_mode 0)
			)
			(polygon
				(pts
					(xy 251.206 -139.827) (xy 251.714 -139.827) (xy 251.714 -140.589) (xy 251.206 -140.589)
				)
			)
		)
	)
)
